FILE_TYPE=LIBRARY_PARTS;
TIME=' Created/Modified on Fri Mar 20 14:22:05 2009' ;
primitive '74LVC1G08GW';
  pin
    'B':
      PIN_NUMBER='(1)';
      INPUT_LOAD='(-0.01,0.01)';
      OUTPUT_LOAD='(1.0,-1.0)';
      BIDIRECTIONAL='TRUE';
    'A':
      PIN_NUMBER='(2)';
      INPUT_LOAD='(-0.01,0.01)';
      OUTPUT_LOAD='(1.0,-1.0)';
      BIDIRECTIONAL='TRUE';
    'Y':
      PIN_NUMBER='(4)';
      INPUT_LOAD='(-0.01,0.01)';
      OUTPUT_LOAD='(1.0,-1.0)';
      BIDIRECTIONAL='TRUE';
    'VCC':
      PIN_NUMBER='(5)';
      PINUSE='POWER';
    'GND':
      PIN_NUMBER='(3)';
      PINUSE='POWER';
  end_pin;
  body
    CLASS='IC';
    PART_NAME='74LVC1G08GW';
    PHYS_DES_PREFIX='U';
  end_body;
end_primitive;
END.
